(kicad_pcb
	(version 20260206)
	(generator "pcbnew")
	(generator_version "10.0")
	(general
		(thickness 1.6)
		(legacy_teardrops no)
	)
	(paper "A4")
	(title_block
		(title "01162023_DA0F0TEBIF0_F0T_Expander_BD_F_brd_V02_OCP.brd")
		(comment 1 "Grand Teton / footprints 4840-4844 of 9728")
	)
	(layers
		(0 "F.Cu" signal "TOP")
		(4 "In1.Cu" signal "GND")
		(6 "In2.Cu" signal "VCC")
		(8 "In3.Cu" signal "VCC1")
		(10 "In4.Cu" signal "GND1")
		(12 "In5.Cu" signal "IN1")
		(14 "In6.Cu" signal "GND2")
		(16 "In7.Cu" signal "IN2")
		(18 "In8.Cu" signal "GND3")
		(20 "In9.Cu" signal "IN3")
		(22 "In10.Cu" signal "GND4")
		(24 "In11.Cu" signal "IN4")
		(26 "In12.Cu" signal "GND5")
		(28 "In13.Cu" signal "IN5")
		(30 "In14.Cu" signal "GND6")
		(32 "In15.Cu" signal "IN6")
		(34 "In16.Cu" signal "GND7")
		(2 "B.Cu" signal "BOTTOM")
		(9 "F.Adhes" user "F.Adhesive")
		(11 "B.Adhes" user "B.Adhesive")
		(13 "F.Paste" user "Package Geometry/Pastemask Top")
		(15 "B.Paste" user "Package Geometry/Pastemask Bottom")
		(5 "F.SilkS" user "Ref Des/Silkscreen Top")
		(7 "B.SilkS" user "Ref Des/Silkscreen Bottom")
		(1 "F.Mask" user "Board Geometry/Soldermask Top")
		(3 "B.Mask" user "Board Geometry/Soldermask Bottom")
		(17 "Dwgs.User" user "User.Drawings")
		(19 "Cmts.User" user "User.Comments")
		(21 "Eco1.User" user "User.Eco1")
		(23 "Eco2.User" user "User.Eco2")
		(25 "Edge.Cuts" user "Board Geometry/Outline")
		(27 "Margin" user)
		(31 "F.CrtYd" user "Package Geometry/Place Bound Top")
		(29 "B.CrtYd" user "Package Geometry/Place Bound Bottom")
		(35 "F.Fab" user "Ref Des/Assembly Top")
		(33 "B.Fab" user "Ref Des/Assembly Bottom")
	)
	(footprint ""
		(layer "F.Cu")
		(at 259.389626 -239.958372 180)
		(property "Reference" "U432"
			(at 1.700784 -4.67487 0)
			(unlocked yes)
			(layer "F.SilkS")
			(effects
				(font
					(size 0.7874 0.5842)
					(thickness 0.1524)
				)
				(justify left)
			)
		)
		(property "Value" ""
			(at 0 0 180)
			(layer "F.Fab")
			(effects
				(font
					(size 1.27 1.27)
				)
			)
		)
		(duplicate_pad_numbers_are_jumpers no)
		(fp_line
			(start 1.525016 1.525016)
			(end 1.525016 1.3208)
			(stroke
				(width 0.1524)
				(type default)
			)
			(layer "F.SilkS")
		)
		(fp_line
			(start 1.525016 1.525016)
			(end -1.525016 1.525016)
			(stroke
				(width 0.1524)
				(type default)
			)
			(layer "F.SilkS")
		)
		(fp_line
			(start 1.525016 -1.3208)
			(end 1.525016 -1.525016)
			(stroke
				(width 0.1524)
				(type default)
			)
			(layer "F.SilkS")
		)
		(fp_line
			(start 1.525016 -1.525016)
			(end 0.9398 -1.525016)
			(stroke
				(width 0.1524)
				(type default)
			)
			(layer "F.SilkS")
		)
		(fp_line
			(start 1.525016 -1.525016)
			(end -1.525016 -1.525016)
			(stroke
				(width 0.1524)
				(type default)
			)
			(layer "F.SilkS")
		)
		(fp_line
			(start 0.9906 1.525016)
			(end 1.525016 1.525016)
			(stroke
				(width 0.1524)
				(type default)
			)
			(layer "F.SilkS")
		)
		(fp_line
			(start -0.8636 -1.525016)
			(end -1.525016 -1.525016)
			(stroke
				(width 0.1524)
				(type default)
			)
			(layer "F.SilkS")
		)
		(fp_line
			(start -1.525016 1.525016)
			(end -0.889 1.525016)
			(stroke
				(width 0.1524)
				(type default)
			)
			(layer "F.SilkS")
		)
		(fp_line
			(start -1.525016 1.3208)
			(end -1.525016 1.525016)
			(stroke
				(width 0.1524)
				(type default)
			)
			(layer "F.SilkS")
		)
		(fp_line
			(start -1.525016 -1.525016)
			(end -1.525016 -1.3208)
			(stroke
				(width 0.1524)
				(type default)
			)
			(layer "F.SilkS")
		)
		(fp_poly
			(pts
				(xy -2.0701 -0.999998) (xy -2.970276 -1.299972) (xy -2.970276 -0.700024)
			)
			(stroke
				(width 0)
				(type default)
			)
			(fill yes)
			(layer "F.SilkS")
		)
		(fp_line
			(start 1.525016 1.525016)
			(end -1.525016 1.525016)
			(stroke
				(width 0.1)
				(type default)
			)
			(layer "F.Fab")
		)
		(fp_line
			(start 1.525016 -1.525016)
			(end 1.525016 1.525016)
			(stroke
				(width 0.1)
				(type default)
			)
			(layer "F.Fab")
		)
		(fp_line
			(start -1.525016 1.525016)
			(end -1.525016 -1.525016)
			(stroke
				(width 0.1)
				(type default)
			)
			(layer "F.Fab")
		)
		(fp_line
			(start -1.525016 -1.525016)
			(end 1.525016 -1.525016)
			(stroke
				(width 0.1)
				(type default)
			)
			(layer "F.Fab")
		)
		(fp_poly
			(pts
				(xy -2.0701 -0.999998) (xy -2.977896 -1.302512) (xy -2.977896 -0.697484)
			)
			(stroke
				(width 0)
				(type default)
			)
			(fill yes)
			(layer "F.Fab")
		)
		(pad "1" smd rect
			(at -1.550162 -0.999998 90)
			(size 0.2794 0.9144)
			(layers "F.Cu" "F.Mask" "F.Paste")
			(net "P1V8_PLL0_PEX2")
		)
		(pad "2" smd rect
			(at -1.550162 -0.500126 90)
			(size 0.2794 0.9144)
			(layers "F.Cu" "F.Mask" "F.Paste")
			(net "P1V8_PLL0_PEX2")
		)
		(pad "3" smd rect
			(at -1.550162 0 90)
			(size 0.2794 0.9144)
			(layers "F.Cu" "F.Mask" "F.Paste")
			(net "P1V8_PLL0_PEX2")
		)
		(pad "4" smd rect
			(at -1.550162 0.500126 90)
			(size 0.2794 0.9144)
			(layers "F.Cu" "F.Mask" "F.Paste")
			(net "P1V8_PLL_PEX2_ADJ")
		)
		(pad "5" smd rect
			(at -1.550162 0.999998 270)
			(size 0.2794 0.9144)
			(layers "F.Cu" "F.Mask" "F.Paste")
			(net "PWRGD_PEX2_P1V8_PLL")
		)
		(pad "6" smd rect
			(at 1.550162 0.999998 270)
			(size 0.2794 0.9144)
			(layers "F.Cu" "F.Mask" "F.Paste")
			(net "PEX2_P1V8_PLL_EN")
		)
		(pad "7" smd rect
			(at 1.550162 0.500126 90)
			(size 0.2794 0.9144)
			(layers "F.Cu" "F.Mask" "F.Paste")
			(net "P3V3_AUX")
		)
		(pad "8" smd rect
			(at 1.550162 0 90)
			(size 0.2794 0.9144)
			(layers "F.Cu" "F.Mask" "F.Paste")
			(net "P3V3_AUX")
		)
		(pad "9" smd rect
			(at 1.550162 -0.500126 90)
			(size 0.2794 0.9144)
			(layers "F.Cu" "F.Mask" "F.Paste")
			(net "P3V3_AUX")
		)
		(pad "10" smd rect
			(at 1.550162 -0.999998 90)
			(size 0.2794 0.9144)
			(layers "F.Cu" "F.Mask" "F.Paste")
			(net "P5V_AUX")
		)
		(pad "TH" smd rect
			(at 0 0 180)
			(size 1.7526 2.667)
			(layers "F.Cu" "F.Mask" "F.Paste")
			(net "GND")
		)
		(zone
			(layer "F.Cu")
			(hatch none 0.5)
			(connect_pads
				(clearance 0)
			)
			(min_thickness 0.25)
			(keepout
				(tracks not_allowed)
				(vias allowed)
				(pads allowed)
				(copperpour not_allowed)
				(footprints allowed)
			)
			(placement
				(enabled no)
				(sheetname "")
			)
			(fill
				(thermal_gap 0.5)
				(thermal_bridge_width 0.5)
				(island_removal_mode 0)
			)
			(polygon
				(pts
					(xy 260.406388 -238.424974) (xy 260.406388 -241.472974) (xy 258.374388 -241.472974) (xy 258.374388 -238.424974)
					(xy 260.304788 -238.424974) (xy 260.304788 -238.551974) (xy 258.450588 -238.551974) (xy 258.450588 -241.371374)
					(xy 260.330188 -241.371374) (xy 260.330188 -238.424974)
				)
			)
		)
	)
	(footprint ""
		(layer "F.Cu")
		(at 26.267918 -55.083456)
		(property "Reference" "PC385"
			(at 0 0 0)
			(layer "F.SilkS")
			(hide yes)
			(effects
				(font
					(size 1.27 1.27)
				)
			)
		)
		(property "Value" ""
			(at 0 0 0)
			(layer "F.Fab")
			(effects
				(font
					(size 1.27 1.27)
				)
			)
		)
		(duplicate_pad_numbers_are_jumpers no)
		(fp_line
			(start -0.7874 -0.4064)
			(end 0.7874 -0.4064)
			(stroke
				(width 0.1524)
				(type default)
			)
			(layer "F.SilkS")
		)
		(fp_line
			(start -0.7874 0.4064)
			(end -0.7874 -0.4064)
			(stroke
				(width 0.1524)
				(type default)
			)
			(layer "F.SilkS")
		)
		(fp_line
			(start 0.7874 -0.4064)
			(end 0.7874 0.4064)
			(stroke
				(width 0.1524)
				(type default)
			)
			(layer "F.SilkS")
		)
		(fp_line
			(start 0.7874 0.4064)
			(end -0.7874 0.4064)
			(stroke
				(width 0.1524)
				(type default)
			)
			(layer "F.SilkS")
		)
		(fp_line
			(start -0.67945 -0.305054)
			(end -0.12065 -0.305054)
			(stroke
				(width 0.1)
				(type default)
			)
			(layer "F.Fab")
		)
		(fp_line
			(start -0.67945 0.3048)
			(end -0.67945 -0.305054)
			(stroke
				(width 0.1)
				(type default)
			)
			(layer "F.Fab")
		)
		(fp_line
			(start -0.12065 -0.305054)
			(end -0.12065 -0.2794)
			(stroke
				(width 0.1)
				(type default)
			)
			(layer "F.Fab")
		)
		(fp_line
			(start -0.12065 -0.2794)
			(end 0.12065 -0.2794)
			(stroke
				(width 0.1)
				(type default)
			)
			(layer "F.Fab")
		)
		(fp_line
			(start -0.12065 0.2794)
			(end -0.12065 0.3048)
			(stroke
				(width 0.1)
				(type default)
			)
			(layer "F.Fab")
		)
		(fp_line
			(start -0.12065 0.3048)
			(end -0.67945 0.3048)
			(stroke
				(width 0.1)
				(type default)
			)
			(layer "F.Fab")
		)
		(fp_line
			(start 0.120396 0.2794)
			(end -0.12065 0.2794)
			(stroke
				(width 0.1)
				(type default)
			)
			(layer "F.Fab")
		)
		(fp_line
			(start 0.120396 0.3048)
			(end 0.120396 0.2794)
			(stroke
				(width 0.1)
				(type default)
			)
			(layer "F.Fab")
		)
		(fp_line
			(start 0.12065 -0.3048)
			(end 0.67945 -0.3048)
			(stroke
				(width 0.1)
				(type default)
			)
			(layer "F.Fab")
		)
		(fp_line
			(start 0.12065 -0.2794)
			(end 0.12065 -0.3048)
			(stroke
				(width 0.1)
				(type default)
			)
			(layer "F.Fab")
		)
		(fp_line
			(start 0.67945 -0.3048)
			(end 0.67945 0.3048)
			(stroke
				(width 0.1)
				(type default)
			)
			(layer "F.Fab")
		)
		(fp_line
			(start 0.67945 0.3048)
			(end 0.120396 0.3048)
			(stroke
				(width 0.1)
				(type default)
			)
			(layer "F.Fab")
		)
		(pad "1" smd circle
			(at -0.40005 0)
			(size 0 0)
			(layers "F.Cu" "F.Mask" "F.Paste")
			(net "P5V_AUX")
		)
		(pad "2" smd circle
			(at 0.40005 0)
			(size 0 0)
			(layers "F.Cu" "F.Mask" "F.Paste")
			(net "GND")
		)
	)
	(footprint ""
		(layer "F.Cu")
		(at 262.281924 -296.191432 180)
		(property "Reference" "C3378"
			(at 0 0 180)
			(layer "F.SilkS")
			(hide yes)
			(effects
				(font
					(size 1.27 1.27)
				)
			)
		)
		(property "Value" ""
			(at 0 0 180)
			(layer "F.Fab")
			(effects
				(font
					(size 1.27 1.27)
				)
			)
		)
		(duplicate_pad_numbers_are_jumpers no)
		(fp_line
			(start 1.2954 0.5842)
			(end -1.2954 0.5842)
			(stroke
				(width 0.1524)
				(type default)
			)
			(layer "F.SilkS")
		)
		(fp_line
			(start 1.2954 -0.5842)
			(end 1.2954 0.5842)
			(stroke
				(width 0.1524)
				(type default)
			)
			(layer "F.SilkS")
		)
		(fp_line
			(start -1.2954 0.5842)
			(end -1.2954 -0.5842)
			(stroke
				(width 0.1524)
				(type default)
			)
			(layer "F.SilkS")
		)
		(fp_line
			(start -1.2954 -0.5842)
			(end 1.2954 -0.5842)
			(stroke
				(width 0.1524)
				(type default)
			)
			(layer "F.SilkS")
		)
		(fp_line
			(start 1.1938 0.4064)
			(end 0.8636 0.4064)
			(stroke
				(width 0.1)
				(type default)
			)
			(layer "F.Fab")
		)
		(fp_line
			(start 1.1938 -0.4064)
			(end 1.1938 0.4064)
			(stroke
				(width 0.1)
				(type default)
			)
			(layer "F.Fab")
		)
		(fp_line
			(start 0.8636 0.4572)
			(end -0.8636 0.4572)
			(stroke
				(width 0.1)
				(type default)
			)
			(layer "F.Fab")
		)
		(fp_line
			(start 0.8636 0.4064)
			(end 0.8636 0.4572)
			(stroke
				(width 0.1)
				(type default)
			)
			(layer "F.Fab")
		)
		(fp_line
			(start 0.8636 -0.4064)
			(end 1.1938 -0.4064)
			(stroke
				(width 0.1)
				(type default)
			)
			(layer "F.Fab")
		)
		(fp_line
			(start 0.8636 -0.4572)
			(end 0.8636 -0.4064)
			(stroke
				(width 0.1)
				(type default)
			)
			(layer "F.Fab")
		)
		(fp_line
			(start -0.8636 0.4572)
			(end -0.8636 0.4064)
			(stroke
				(width 0.1)
				(type default)
			)
			(layer "F.Fab")
		)
		(fp_line
			(start -0.8636 0.4064)
			(end -1.1938 0.4064)
			(stroke
				(width 0.1)
				(type default)
			)
			(layer "F.Fab")
		)
		(fp_line
			(start -0.8636 -0.4064)
			(end -0.8636 -0.4572)
			(stroke
				(width 0.1)
				(type default)
			)
			(layer "F.Fab")
		)
		(fp_line
			(start -0.8636 -0.4572)
			(end 0.8636 -0.4572)
			(stroke
				(width 0.1)
				(type default)
			)
			(layer "F.Fab")
		)
		(fp_line
			(start -1.1938 0.4064)
			(end -1.1938 -0.4064)
			(stroke
				(width 0.1)
				(type default)
			)
			(layer "F.Fab")
		)
		(fp_line
			(start -1.1938 -0.4064)
			(end -0.8636 -0.4064)
			(stroke
				(width 0.1)
				(type default)
			)
			(layer "F.Fab")
		)
		(pad "1" smd rect
			(at -0.7366 0 90)
			(size 0.7112 0.8128)
			(layers "F.Cu" "F.Mask" "F.Paste")
			(net "PCEPLL0_VDDA18_PEX2_R")
		)
		(pad "2" smd rect
			(at 0.7366 0 90)
			(size 0.7112 0.8128)
			(layers "F.Cu" "F.Mask" "F.Paste")
			(net "GND")
		)
	)
	(footprint ""
		(layer "F.Cu")
		(at 483.480364 -528.154392 180)
		(property "Reference" "PEX2_HS"
			(at 0.127 -0.593598 0)
			(unlocked yes)
			(layer "F.SilkS")
			(effects
				(font
					(size 0.254 0.127)
					(thickness 0.000001)
				)
			)
		)
		(property "Value" ""
			(at 0 0 180)
			(layer "F.Fab")
			(effects
				(font
					(size 1.27 1.27)
				)
			)
		)
		(duplicate_pad_numbers_are_jumpers no)
		(pad "1" smd circle
			(at 0 0 180)
			(size 0.762 0.762)
			(layers "F.Cu" "F.Mask" "F.Paste")
			(net "Net_9122")
		)
	)
	(footprint ""
		(layer "F.Cu")
		(at 358.830626 -144.067276 180)
		(property "Reference" "PC823"
			(at 0 0 180)
			(layer "F.SilkS")
			(hide yes)
			(effects
				(font
					(size 1.27 1.27)
				)
			)
		)
		(property "Value" ""
			(at 0 0 180)
			(layer "F.Fab")
			(effects
				(font
					(size 1.27 1.27)
				)
			)
		)
		(duplicate_pad_numbers_are_jumpers no)
		(fp_line
			(start 1.524 0.762)
			(end -1.524 0.762)
			(stroke
				(width 0.1524)
				(type default)
			)
			(layer "F.SilkS")
		)
		(fp_line
			(start 1.524 -0.762)
			(end 1.524 0.762)
			(stroke
				(width 0.1524)
				(type default)
			)
			(layer "F.SilkS")
		)
		(fp_line
			(start -1.524 0.762)
			(end -1.524 -0.762)
			(stroke
				(width 0.1524)
				(type default)
			)
			(layer "F.SilkS")
		)
		(fp_line
			(start -1.524 -0.762)
			(end 1.524 -0.762)
			(stroke
				(width 0.1524)
				(type default)
			)
			(layer "F.SilkS")
		)
		(fp_line
			(start 1.1049 0.724916)
			(end 1.1049 -0.724916)
			(stroke
				(width 0.1)
				(type default)
			)
			(layer "F.Fab")
		)
		(fp_line
			(start 1.1049 -0.724916)
			(end -1.1049 -0.724916)
			(stroke
				(width 0.1)
				(type default)
			)
			(layer "F.Fab")
		)
		(fp_line
			(start -1.1049 0.724916)
			(end 1.1049 0.724916)
			(stroke
				(width 0.1)
				(type default)
			)
			(layer "F.Fab")
		)
		(fp_line
			(start -1.1049 -0.724916)
			(end -1.1049 0.724916)
			(stroke
				(width 0.1)
				(type default)
			)
			(layer "F.Fab")
		)
		(pad "1" smd rect
			(at -0.889 0)
			(size 1.016 1.27)
			(layers "F.Cu" "F.Mask" "F.Paste")
			(net "P12V_NIC6_R")
		)
		(pad "2" smd rect
			(at 0.889 0)
			(size 1.016 1.27)
			(layers "F.Cu" "F.Mask" "F.Paste")
			(net "GND")
		)
	)
)
